
INPUT-UNITS     INCHES

WHEEL     1

RECTANGLE         28        32   0.00000  D10
RECTANGLE         32        28   0.00000  D11
RECTANGLE         32        36   0.00000  D12
RECTANGLE         36        32   0.00000  D13
RECTANGLE         46        62   0.00000  D14
RECTANGLE         62        46   0.00000  D15
RECTANGLE         50        66   0.00000  D16
RECTANGLE         66        50   0.00000  D17
RECTANGLE         11        36   0.00000  D18
RECTANGLE         36        11   0.00000  D19
RECTANGLE         15        40   0.00000  D20
RECTANGLE         40        15   0.00000  D21
SQUARE           109   0.00000            D22
SQUARE           113   0.00000            D23
RECTANGLE         18        20   0.00000  D24
RECTANGLE         20        18   0.00000  D25
RECTANGLE         22        24   0.00000  D26
RECTANGLE         24        22   0.00000  D27
RECTANGLE         87       174   0.00000  D28
RECTANGLE        174        87   0.00000  D29
RECTANGLE         91       178   0.00000  D30
RECTANGLE        178        91   0.00000  D31
CIRCLE           155            D32
FLASH     TR141X155X40-45      0.00000  D33
CIRCLE           125            D34
CIRCLE           145            D35
CIRCLE            87            D36
FLASH     TR83X97X25-45        0.00000  D37
CIRCLE            85            D38
CIRCLE           272            D39
FLASH     TR268X282X40-45      0.00000  D40
CIRCLE           400            D41
LINE             394            D42
OBLONG           394      1260   0.00000  D43
OBLONG          1260       394   0.00000  D44
CIRCLE           404            D45
LINE             398            D46
OBLONG           398      1264   0.00000  D47
OBLONG          1264       398   0.00000  D48
FLASH     TR_C10-ALL           0.00000  D49
LINE             355            D50
OBLONG           355       827   0.00000  D51
OBLONG           827       355   0.00000  D52
LINE             359            D53
OBLONG           359       831   0.00000  D54
OBLONG           831       359   0.00000  D55
CIRCLE            89            D56
FLASH     TR75X89X15-45        0.00000  D57
CIRCLE            59            D58
CIRCLE            79            D59
CIRCLE            58            D60
FLASH     TR54X68X15-45        0.00000  D61
CIRCLE            54            D62
SQUARE            54   0.00000            D63
SQUARE            58   0.00000            D64
RECTANGLE         22        68   0.00000  D65
RECTANGLE         68        22   0.00000  D66
RECTANGLE         26        72   0.00000  D67
RECTANGLE         72        26   0.00000  D68
RECTANGLE         16        24   0.00000  D69
RECTANGLE         24        16   0.00000  D70
RECTANGLE         20        28   0.00000  D71
RECTANGLE         28        20   0.00000  D72
RECTANGLE         24        24   0.00000  D73
RECTANGLE         28        28   0.00000  D74
RECTANGLE         20        20   0.00000  D75
RECTANGLE         13        46   0.00000  D76
RECTANGLE         46        13   0.00000  D77
RECTANGLE         17        50   0.00000  D78
RECTANGLE         50        17   0.00000  D79
RECTANGLE         24        32   0.00000  D80
RECTANGLE         32        24   0.00000  D81
RECTANGLE         28        36   0.00000  D82
RECTANGLE         36        28   0.00000  D83
RECTANGLE         32        40   0.00000  D84
RECTANGLE         40        32   0.00000  D85
RECTANGLE         14        59   0.00000  D86
RECTANGLE         59        14   0.00000  D87
RECTANGLE         18        63   0.00000  D88
RECTANGLE         63        18   0.00000  D89
SQUARE           107   0.00000            D90
SQUARE           111   0.00000            D91
RECTANGLE          7        32   0.00000  D92
RECTANGLE         32         7   0.00000  D93
RECTANGLE         16        20   0.00000  D94
RECTANGLE         20        16   0.00000  D95
RECTANGLE         20        24   0.00000  D96
RECTANGLE         24        20   0.00000  D97
RECTANGLE          7        36   0.00000  D98
RECTANGLE         36         7   0.00000  D99
RECTANGLE         11        40   0.00000  D100
RECTANGLE         40        11   0.00000  D101
RECTANGLE         12        99   0.00000  D102
RECTANGLE         99        12   0.00000  D103
RECTANGLE         16       103   0.00000  D104
RECTANGLE        103        16   0.00000  D105
RECTANGLE         95       130   0.00000  D106
RECTANGLE        130        95   0.00000  D107
RECTANGLE         99       134   0.00000  D108
RECTANGLE        134        99   0.00000  D109
RECTANGLE         99       130   0.00000  D110
RECTANGLE        130        99   0.00000  D111
RECTANGLE        103       134   0.00000  D112
RECTANGLE        134       103   0.00000  D113
RECTANGLE         32       197   0.00000  D114
RECTANGLE        197        32   0.00000  D115
RECTANGLE         36       201   0.00000  D116
RECTANGLE        201        36   0.00000  D117
RECTANGLE        173       248   0.00000  D118
RECTANGLE        248       173   0.00000  D119
RECTANGLE        177       252   0.00000  D120
RECTANGLE        252       177   0.00000  D121
RECTANGLE         26        28   0.00000  D122
RECTANGLE         28        26   0.00000  D123
RECTANGLE         32        34   0.00000  D124
RECTANGLE         34        32   0.00000  D125
RECTANGLE         36        38   0.00000  D126
RECTANGLE         38        36   0.00000  D127
RECTANGLE         40        50   0.00000  D128
RECTANGLE         50        40   0.00000  D129
RECTANGLE         44        54   0.00000  D130
RECTANGLE         54        44   0.00000  D131
CIRCLE            30            D132
FLASH     TR_C5-ALL            0.00000  D133
CIRCLE            20            D134
CIRCLE            34            D135
CIRCLE            26            D136
CIRCLE            39            D137
CIRCLE           118            D138
LINE               6            D139
LINE               2            D140
LINE               1            D141
LINE              11            D142
LINE              18            D143
LINE               4            D144
LINE               8            D145
LINE              10            D146
LINE              25            D147
LINE               9            D148
LINE              14            D149
LINE              13            D150
LINE               7            D151
LINE              15            D152
LINE              40            D153
LINE             100            D154
LINE              20            D155
LINE             248            D156
LINE              54            D157
LINE              32            D158

